# T6G (Grand Teton) — schematic netlist excerpt (pin names and nets, part order shuffled) for the footprints in the layout excerpt that follows; sources: Cadence DE-HDL packaged netlist, KiCad conversion of 04192023_DAF0TMB3IC0_F0TG_MB_C_brd_V02_OCP.brd

C1540  Q_CAP_DIFFBUS  DIFF BUS_0.22UF 6.3V 20% X6S  pkg C0201  page 67 : \1\ = P5E_CPU1_P3_TX_C_DN<3> ; \2\ = P5E_CPU1_P3_TX_DN<3>
C1060  Q_CAP  0.1UF 25V 10% X7R  pkg 0402  page 136 : A = P3V3_AUX ; B = GND
PC2092  Q_CAP  0.1UF 25V 10% X7R  pkg 0402  page 134 : A = P12V_OCP_SFF ; B = GND

(kicad_pcb
	(version 20260206)
	(generator "pcbnew")
	(generator_version "10.0")
	(general
		(thickness 1.6)
		(legacy_teardrops no)
	)
	(paper "A4")
	(title_block
		(title "04192023_DAF0TMB3IC0_F0TG_MB_C_brd_V02_OCP.brd")
		(comment 1 "Grand Teton / footprints 1156-1158 of 8354")
	)
	(layers
		(0 "F.Cu" signal "TOP")
		(4 "In1.Cu" signal "GND")
		(6 "In2.Cu" signal "IN1")
		(8 "In3.Cu" signal "GND1")
		(10 "In4.Cu" signal "IN2")
		(12 "In5.Cu" signal "GND2")
		(14 "In6.Cu" signal "IN3")
		(16 "In7.Cu" signal "GND3")
		(18 "In8.Cu" signal "VCC")
		(20 "In9.Cu" signal "VCC1")
		(22 "In10.Cu" signal "GND4")
		(24 "In11.Cu" signal "IN4")
		(26 "In12.Cu" signal "GND5")
		(28 "In13.Cu" signal "IN5")
		(30 "In14.Cu" signal "GND6")
		(32 "In15.Cu" signal "IN6")
		(34 "In16.Cu" signal "GND7")
		(2 "B.Cu" signal "BOTTOM")
		(9 "F.Adhes" user "F.Adhesive")
		(11 "B.Adhes" user "B.Adhesive")
		(13 "F.Paste" user "Package Geometry/Pastemask Top")
		(15 "B.Paste" user "Package Geometry/Pastemask Bottom")
		(5 "F.SilkS" user "Ref Des/Silkscreen Top")
		(7 "B.SilkS" user "Ref Des/Silkscreen Bottom")
		(1 "F.Mask" user "Board Geometry/Soldermask Top")
		(3 "B.Mask" user "Board Geometry/Soldermask Bottom")
		(17 "Dwgs.User" user "User.Drawings")
		(19 "Cmts.User" user "User.Comments")
		(21 "Eco1.User" user "User.Eco1")
		(23 "Eco2.User" user "User.Eco2")
		(25 "Edge.Cuts" user "Board Geometry/Outline")
		(27 "Margin" user)
		(31 "F.CrtYd" user "Package Geometry/Place Bound Top")
		(29 "B.CrtYd" user "Package Geometry/Place Bound Bottom")
		(35 "F.Fab" user "Ref Des/Assembly Top")
		(33 "B.Fab" user "Ref Des/Assembly Bottom")
	)
	(footprint ""
		(layer "F.Cu")
		(at 445.753744 -21.693378)
		(property "Reference" "PC2092"
			(at 0 0 0)
			(layer "F.SilkS")
			(hide yes)
			(effects
				(font
					(size 1.27 1.27)
				)
			)
		)
		(property "Value" ""
			(at 0 0 0)
			(layer "F.Fab")
			(effects
				(font
					(size 1.27 1.27)
				)
			)
		)
		(duplicate_pad_numbers_are_jumpers no)
		(fp_line
			(start -0.7874 -0.4064)
			(end 0.7874 -0.4064)
			(stroke
				(width 0.1524)
				(type default)
			)
			(layer "F.SilkS")
		)
		(fp_line
			(start -0.7874 0.4064)
			(end -0.7874 -0.4064)
			(stroke
				(width 0.1524)
				(type default)
			)
			(layer "F.SilkS")
		)
		(fp_line
			(start 0.7874 -0.4064)
			(end 0.7874 0.4064)
			(stroke
				(width 0.1524)
				(type default)
			)
			(layer "F.SilkS")
		)
		(fp_line
			(start 0.7874 0.4064)
			(end -0.7874 0.4064)
			(stroke
				(width 0.1524)
				(type default)
			)
			(layer "F.SilkS")
		)
		(fp_line
			(start -0.67945 -0.305054)
			(end -0.12065 -0.305054)
			(stroke
				(width 0.1)
				(type default)
			)
			(layer "F.Fab")
		)
		(fp_line
			(start -0.67945 0.3048)
			(end -0.67945 -0.305054)
			(stroke
				(width 0.1)
				(type default)
			)
			(layer "F.Fab")
		)
		(fp_line
			(start -0.12065 -0.305054)
			(end -0.12065 -0.2794)
			(stroke
				(width 0.1)
				(type default)
			)
			(layer "F.Fab")
		)
		(fp_line
			(start -0.12065 -0.2794)
			(end 0.12065 -0.2794)
			(stroke
				(width 0.1)
				(type default)
			)
			(layer "F.Fab")
		)
		(fp_line
			(start -0.12065 0.2794)
			(end -0.12065 0.3048)
			(stroke
				(width 0.1)
				(type default)
			)
			(layer "F.Fab")
		)
		(fp_line
			(start -0.12065 0.3048)
			(end -0.67945 0.3048)
			(stroke
				(width 0.1)
				(type default)
			)
			(layer "F.Fab")
		)
		(fp_line
			(start 0.120396 0.2794)
			(end -0.12065 0.2794)
			(stroke
				(width 0.1)
				(type default)
			)
			(layer "F.Fab")
		)
		(fp_line
			(start 0.120396 0.3048)
			(end 0.120396 0.2794)
			(stroke
				(width 0.1)
				(type default)
			)
			(layer "F.Fab")
		)
		(fp_line
			(start 0.12065 -0.3048)
			(end 0.67945 -0.3048)
			(stroke
				(width 0.1)
				(type default)
			)
			(layer "F.Fab")
		)
		(fp_line
			(start 0.12065 -0.2794)
			(end 0.12065 -0.3048)
			(stroke
				(width 0.1)
				(type default)
			)
			(layer "F.Fab")
		)
		(fp_line
			(start 0.67945 -0.3048)
			(end 0.67945 0.3048)
			(stroke
				(width 0.1)
				(type default)
			)
			(layer "F.Fab")
		)
		(fp_line
			(start 0.67945 0.3048)
			(end 0.120396 0.3048)
			(stroke
				(width 0.1)
				(type default)
			)
			(layer "F.Fab")
		)
		(pad "1" smd circle
			(at -0.40005 0)
			(size 0 0)
			(layers "F.Cu" "F.Mask" "F.Paste")
			(net "P12V_OCP_SFF")
		)
		(pad "2" smd circle
			(at 0.40005 0)
			(size 0 0)
			(layers "F.Cu" "F.Mask" "F.Paste")
			(net "GND")
		)
	)
	(footprint ""
		(layer "F.Cu")
		(at 112.705896 -370.57203 -90)
		(property "Reference" "C1540"
			(at 0 0 270)
			(layer "F.SilkS")
			(hide yes)
			(effects
				(font
					(size 1.27 1.27)
				)
			)
		)
		(property "Value" ""
			(at 0 0 270)
			(layer "F.Fab")
			(effects
				(font
					(size 1.27 1.27)
				)
			)
		)
		(duplicate_pad_numbers_are_jumpers no)
		(fp_line
			(start -0.299974 0.150114)
			(end -0.299974 -0.150114)
			(stroke
				(width 0.1)
				(type default)
			)
			(layer "F.Fab")
		)
		(fp_line
			(start 0.299974 0.150114)
			(end -0.299974 0.150114)
			(stroke
				(width 0.1)
				(type default)
			)
			(layer "F.Fab")
		)
		(fp_line
			(start -0.299974 -0.150114)
			(end 0.299974 -0.150114)
			(stroke
				(width 0.1)
				(type default)
			)
			(layer "F.Fab")
		)
		(fp_line
			(start 0.299974 -0.150114)
			(end 0.299974 0.150114)
			(stroke
				(width 0.1)
				(type default)
			)
			(layer "F.Fab")
		)
		(pad "1" smd rect
			(at -0.2667 0 270)
			(size 0.3048 0.381)
			(layers "F.Cu" "F.Mask" "F.Paste")
			(net "P5E_CPU1_P3_TX_C_DN<3>")
		)
		(pad "2" smd rect
			(at 0.2667 0 270)
			(size 0.3048 0.381)
			(layers "F.Cu" "F.Mask" "F.Paste")
			(net "P5E_CPU1_P3_TX_DN<3>")
		)
	)
	(footprint ""
		(layer "F.Cu")
		(at 212.598 -120.65 180)
		(property "Reference" "C1060"
			(at 0 0 180)
			(layer "F.SilkS")
			(hide yes)
			(effects
				(font
					(size 1.27 1.27)
				)
			)
		)
		(property "Value" ""
			(at 0 0 180)
			(layer "F.Fab")
			(effects
				(font
					(size 1.27 1.27)
				)
			)
		)
		(duplicate_pad_numbers_are_jumpers no)
		(fp_line
			(start 0.7874 0.4064)
			(end -0.7874 0.4064)
			(stroke
				(width 0.1524)
				(type default)
			)
			(layer "F.SilkS")
		)
		(fp_line
			(start 0.7874 -0.4064)
			(end 0.7874 0.4064)
			(stroke
				(width 0.1524)
				(type default)
			)
			(layer "F.SilkS")
		)
		(fp_line
			(start -0.7874 0.4064)
			(end -0.7874 -0.4064)
			(stroke
				(width 0.1524)
				(type default)
			)
			(layer "F.SilkS")
		)
		(fp_line
			(start -0.7874 -0.4064)
			(end 0.7874 -0.4064)
			(stroke
				(width 0.1524)
				(type default)
			)
			(layer "F.SilkS")
		)
		(fp_line
			(start 0.67945 0.3048)
			(end 0.120396 0.3048)
			(stroke
				(width 0.1)
				(type default)
			)
			(layer "F.Fab")
		)
		(fp_line
			(start 0.67945 -0.3048)
			(end 0.67945 0.3048)
			(stroke
				(width 0.1)
				(type default)
			)
			(layer "F.Fab")
		)
		(fp_line
			(start 0.12065 -0.2794)
			(end 0.12065 -0.3048)
			(stroke
				(width 0.1)
				(type default)
			)
			(layer "F.Fab")
		)
		(fp_line
			(start 0.12065 -0.3048)
			(end 0.67945 -0.3048)
			(stroke
				(width 0.1)
				(type default)
			)
			(layer "F.Fab")
		)
		(fp_line
			(start 0.120396 0.3048)
			(end 0.120396 0.2794)
			(stroke
				(width 0.1)
				(type default)
			)
			(layer "F.Fab")
		)
		(fp_line
			(start 0.120396 0.2794)
			(end -0.12065 0.2794)
			(stroke
				(width 0.1)
				(type default)
			)
			(layer "F.Fab")
		)
		(fp_line
			(start -0.12065 0.3048)
			(end -0.67945 0.3048)
			(stroke
				(width 0.1)
				(type default)
			)
			(layer "F.Fab")
		)
		(fp_line
			(start -0.12065 0.2794)
			(end -0.12065 0.3048)
			(stroke
				(width 0.1)
				(type default)
			)
			(layer "F.Fab")
		)
		(fp_line
			(start -0.12065 -0.2794)
			(end 0.12065 -0.2794)
			(stroke
				(width 0.1)
				(type default)
			)
			(layer "F.Fab")
		)
		(fp_line
			(start -0.12065 -0.305054)
			(end -0.12065 -0.2794)
			(stroke
				(width 0.1)
				(type default)
			)
			(layer "F.Fab")
		)
		(fp_line
			(start -0.67945 0.3048)
			(end -0.67945 -0.305054)
			(stroke
				(width 0.1)
				(type default)
			)
			(layer "F.Fab")
		)
		(fp_line
			(start -0.67945 -0.305054)
			(end -0.12065 -0.305054)
			(stroke
				(width 0.1)
				(type default)
			)
			(layer "F.Fab")
		)
		(pad "1" smd circle
			(at -0.40005 0 180)
			(size 0 0)
			(layers "F.Cu" "F.Mask" "F.Paste")
			(net "P3V3_AUX")
		)
		(pad "2" smd circle
			(at 0.40005 0 180)
			(size 0 0)
			(layers "F.Cu" "F.Mask" "F.Paste")
			(net "GND")
		)
	)
)
